# T6G (Grand Teton) — schematic netlist excerpt (pin names and nets, part order shuffled) for the footprints in the layout excerpt that follows; sources: Cadence DE-HDL packaged netlist, KiCad conversion of 04192023_DAF0TMB3IC0_F0TG_MB_C_brd_V02_OCP.brd

R6505  Q_RES  10K 5% CHIP  pkg 0402LF  page 360 : A = P3V3_AUX ; B = PWRGD_P1V8_RETIMER_CPU0
C432  Q_CAP  100UF 4V 20% X6S  pkg C0805  page 356 : A = P1V8_CPU1_RT_1D ; B = GND
C185  Q_CAP  1UF 4V 20% X6S  pkg 0201  page 323 : A = P0V9_CPU1_RT_2D ; B = GND

(kicad_pcb
	(version 20260206)
	(generator "pcbnew")
	(generator_version "10.0")
	(general
		(thickness 1.6)
		(legacy_teardrops no)
	)
	(paper "A4")
	(title_block
		(title "04192023_DAF0TMB3IC0_F0TG_MB_C_brd_V02_OCP.brd")
		(comment 1 "Grand Teton / footprints 7194-7196 of 8354")
	)
	(layers
		(0 "F.Cu" signal "TOP")
		(4 "In1.Cu" signal "GND")
		(6 "In2.Cu" signal "IN1")
		(8 "In3.Cu" signal "GND1")
		(10 "In4.Cu" signal "IN2")
		(12 "In5.Cu" signal "GND2")
		(14 "In6.Cu" signal "IN3")
		(16 "In7.Cu" signal "GND3")
		(18 "In8.Cu" signal "VCC")
		(20 "In9.Cu" signal "VCC1")
		(22 "In10.Cu" signal "GND4")
		(24 "In11.Cu" signal "IN4")
		(26 "In12.Cu" signal "GND5")
		(28 "In13.Cu" signal "IN5")
		(30 "In14.Cu" signal "GND6")
		(32 "In15.Cu" signal "IN6")
		(34 "In16.Cu" signal "GND7")
		(2 "B.Cu" signal "BOTTOM")
		(9 "F.Adhes" user "F.Adhesive")
		(11 "B.Adhes" user "B.Adhesive")
		(13 "F.Paste" user "Package Geometry/Pastemask Top")
		(15 "B.Paste" user "Package Geometry/Pastemask Bottom")
		(5 "F.SilkS" user "Ref Des/Silkscreen Top")
		(7 "B.SilkS" user "Ref Des/Silkscreen Bottom")
		(1 "F.Mask" user "Board Geometry/Soldermask Top")
		(3 "B.Mask" user "Board Geometry/Soldermask Bottom")
		(17 "Dwgs.User" user "User.Drawings")
		(19 "Cmts.User" user "User.Comments")
		(21 "Eco1.User" user "User.Eco1")
		(23 "Eco2.User" user "User.Eco2")
		(25 "Edge.Cuts" user "Board Geometry/Outline")
		(27 "Margin" user)
		(31 "F.CrtYd" user "Package Geometry/Place Bound Top")
		(29 "B.CrtYd" user "Package Geometry/Place Bound Bottom")
		(35 "F.Fab" user "Ref Des/Assembly Top")
		(33 "B.Fab" user "Ref Des/Assembly Bottom")
	)
	(footprint ""
		(layer "B.Cu")
		(at 238.310928 -290.844732 180)
		(property "Reference" "R6505"
			(at 0 0 0)
			(layer "B.SilkS")
			(hide yes)
			(effects
				(font
					(size 1.27 1.27)
				)
				(justify mirror)
			)
		)
		(property "Value" ""
			(at 0 0 0)
			(layer "B.Fab")
			(effects
				(font
					(size 1.27 1.27)
				)
				(justify mirror)
			)
		)
		(duplicate_pad_numbers_are_jumpers no)
		(fp_line
			(start 0.7874 0.4064)
			(end 0.7874 -0.4064)
			(stroke
				(width 0.1524)
				(type default)
			)
			(layer "B.SilkS")
		)
		(fp_line
			(start 0.7874 -0.4064)
			(end -0.7874 -0.4064)
			(stroke
				(width 0.1524)
				(type default)
			)
			(layer "B.SilkS")
		)
		(fp_line
			(start -0.7874 0.4064)
			(end 0.7874 0.4064)
			(stroke
				(width 0.1524)
				(type default)
			)
			(layer "B.SilkS")
		)
		(fp_line
			(start -0.7874 -0.4064)
			(end -0.7874 0.4064)
			(stroke
				(width 0.1524)
				(type default)
			)
			(layer "B.SilkS")
		)
		(fp_line
			(start 0.67945 0.3048)
			(end 0.67945 -0.305054)
			(stroke
				(width 0.1)
				(type default)
			)
			(layer "B.Fab")
		)
		(fp_line
			(start 0.67945 -0.305054)
			(end 0.12065 -0.305054)
			(stroke
				(width 0.1)
				(type default)
			)
			(layer "B.Fab")
		)
		(fp_line
			(start 0.12065 0.3048)
			(end 0.67945 0.3048)
			(stroke
				(width 0.1)
				(type default)
			)
			(layer "B.Fab")
		)
		(fp_line
			(start 0.12065 0.2794)
			(end 0.12065 0.3048)
			(stroke
				(width 0.1)
				(type default)
			)
			(layer "B.Fab")
		)
		(fp_line
			(start 0.12065 -0.2794)
			(end -0.12065 -0.2794)
			(stroke
				(width 0.1)
				(type default)
			)
			(layer "B.Fab")
		)
		(fp_line
			(start 0.12065 -0.305054)
			(end 0.12065 -0.2794)
			(stroke
				(width 0.1)
				(type default)
			)
			(layer "B.Fab")
		)
		(fp_line
			(start -0.120396 0.3048)
			(end -0.120396 0.2794)
			(stroke
				(width 0.1)
				(type default)
			)
			(layer "B.Fab")
		)
		(fp_line
			(start -0.120396 0.2794)
			(end 0.12065 0.2794)
			(stroke
				(width 0.1)
				(type default)
			)
			(layer "B.Fab")
		)
		(fp_line
			(start -0.12065 -0.2794)
			(end -0.12065 -0.3048)
			(stroke
				(width 0.1)
				(type default)
			)
			(layer "B.Fab")
		)
		(fp_line
			(start -0.12065 -0.3048)
			(end -0.67945 -0.3048)
			(stroke
				(width 0.1)
				(type default)
			)
			(layer "B.Fab")
		)
		(fp_line
			(start -0.67945 0.3048)
			(end -0.120396 0.3048)
			(stroke
				(width 0.1)
				(type default)
			)
			(layer "B.Fab")
		)
		(fp_line
			(start -0.67945 -0.3048)
			(end -0.67945 0.3048)
			(stroke
				(width 0.1)
				(type default)
			)
			(layer "B.Fab")
		)
		(pad "1" smd circle
			(at 0.40005 0)
			(size 0 0)
			(layers "B.Cu" "B.Mask" "B.Paste")
			(net "P3V3_AUX")
		)
		(pad "2" smd circle
			(at -0.40005 0)
			(size 0 0)
			(layers "B.Cu" "B.Mask" "B.Paste")
			(net "PWRGD_P1V8_RETIMER_CPU0")
		)
	)
	(footprint ""
		(layer "B.Cu")
		(at 137.74547 -387.084062 -90)
		(property "Reference" "C432"
			(at 0 0 90)
			(layer "B.SilkS")
			(hide yes)
			(effects
				(font
					(size 1.27 1.27)
				)
				(justify mirror)
			)
		)
		(property "Value" ""
			(at 0 0 90)
			(layer "B.Fab")
			(effects
				(font
					(size 1.27 1.27)
				)
				(justify mirror)
			)
		)
		(duplicate_pad_numbers_are_jumpers no)
		(fp_line
			(start -1.524 0.762)
			(end 1.524 0.762)
			(stroke
				(width 0.1524)
				(type default)
			)
			(layer "B.SilkS")
		)
		(fp_line
			(start 1.524 0.762)
			(end 1.524 -0.762)
			(stroke
				(width 0.1524)
				(type default)
			)
			(layer "B.SilkS")
		)
		(fp_line
			(start -1.524 -0.762)
			(end -1.524 0.762)
			(stroke
				(width 0.1524)
				(type default)
			)
			(layer "B.SilkS")
		)
		(fp_line
			(start 1.524 -0.762)
			(end -1.524 -0.762)
			(stroke
				(width 0.1524)
				(type default)
			)
			(layer "B.SilkS")
		)
		(fp_line
			(start -1.1049 0.724916)
			(end -1.1049 -0.724916)
			(stroke
				(width 0.1)
				(type default)
			)
			(layer "B.Fab")
		)
		(fp_line
			(start 1.1049 0.724916)
			(end -1.1049 0.724916)
			(stroke
				(width 0.1)
				(type default)
			)
			(layer "B.Fab")
		)
		(fp_line
			(start -1.1049 -0.724916)
			(end 1.1049 -0.724916)
			(stroke
				(width 0.1)
				(type default)
			)
			(layer "B.Fab")
		)
		(fp_line
			(start 1.1049 -0.724916)
			(end 1.1049 0.724916)
			(stroke
				(width 0.1)
				(type default)
			)
			(layer "B.Fab")
		)
		(pad "1" smd rect
			(at 0.889 0 270)
			(size 1.016 1.27)
			(layers "B.Cu" "B.Mask" "B.Paste")
			(net "P1V8_CPU1_RT_1D")
		)
		(pad "2" smd rect
			(at -0.889 0 270)
			(size 1.016 1.27)
			(layers "B.Cu" "B.Mask" "B.Paste")
			(net "GND")
		)
	)
	(footprint ""
		(layer "B.Cu")
		(at 59.391296 -390.909302 90)
		(property "Reference" "C185"
			(at 0 0 90)
			(layer "B.SilkS")
			(hide yes)
			(effects
				(font
					(size 1.27 1.27)
				)
				(justify mirror)
			)
		)
		(property "Value" ""
			(at 0 0 90)
			(layer "B.Fab")
			(effects
				(font
					(size 1.27 1.27)
				)
				(justify mirror)
			)
		)
		(duplicate_pad_numbers_are_jumpers no)
		(fp_line
			(start 0.299974 -0.150114)
			(end -0.299974 -0.150114)
			(stroke
				(width 0.1)
				(type default)
			)
			(layer "B.Fab")
		)
		(fp_line
			(start -0.299974 -0.150114)
			(end -0.299974 0.150114)
			(stroke
				(width 0.1)
				(type default)
			)
			(layer "B.Fab")
		)
		(fp_line
			(start 0.299974 0.150114)
			(end 0.299974 -0.150114)
			(stroke
				(width 0.1)
				(type default)
			)
			(layer "B.Fab")
		)
		(fp_line
			(start -0.299974 0.150114)
			(end 0.299974 0.150114)
			(stroke
				(width 0.1)
				(type default)
			)
			(layer "B.Fab")
		)
		(pad "1" smd rect
			(at 0.2667 0 270)
			(size 0.3048 0.381)
			(layers "B.Cu" "B.Mask" "B.Paste")
			(net "P0V9_CPU1_RT_2D")
		)
		(pad "2" smd rect
			(at -0.2667 0 270)
			(size 0.3048 0.381)
			(layers "B.Cu" "B.Mask" "B.Paste")
			(net "GND")
		)
	)
)
